#ISCELL
  logical_power design_note *
  *
#ISCELL
  mstr_misc dns *
  *
#ISCELL
  pure_quanta quanta_title_block_c *
  *
#CELL
  pure_quanta q_res *
  page27_i100
#CELL
  pure_quanta q_res *
  page27_i101
#CELL
  pure_quanta q_res *
  page27_i102
#CELL
  pure_quanta q_res *
  page27_i103
#CELL
  pure_quanta q_res *
  page27_i105
#CELL
  pure_quanta q_res *
  page27_i106
#CELL
  pure_quanta q_res *
  page27_i107
#CELL
  pure_quanta q_res *
  page27_i108
#CELL
  pure_quanta q_res *
  page27_i109
#ISCELL
  logical_power universal_power *
  page27_i110
#ISCELL
  standard offpage *
  page27_i119
#ISCELL
  standard offpage *
  page27_i120
#ISCELL
  standard offpage *
  page27_i121
#ISCELL
  standard offpage *
  page27_i122
#ISCELL
  standard offpage *
  page27_i123
#ISCELL
  standard offpage *
  page27_i124
#ISCELL
  standard offpage *
  page27_i125
#ISCELL
  standard offpage *
  page27_i126
#ISCELL
  standard offpage *
  page27_i127
#ISCELL
  standard offpage *
  page27_i128
#ISCELL
  standard offpage *
  page27_i129
#ISCELL
  standard offpage *
  page27_i130
#ISCELL
  standard offpage *
  page27_i131
#ISCELL
  standard offpage *
  page27_i132
#ISCELL
  standard offpage *
  page27_i133
#ISCELL
  standard offpage *
  page27_i134
#ISCELL
  standard offpage *
  page27_i135
#ISCELL
  standard offpage *
  page27_i136
#ISCELL
  standard offpage *
  page27_i137
#ISCELL
  standard offpage *
  page27_i138
#ISCELL
  standard offpage *
  page27_i139
#ISCELL
  standard offpage *
  page27_i14
#ISCELL
  standard offpage *
  page27_i140
#ISCELL
  standard offpage *
  page27_i141
#ISCELL
  standard offpage *
  page27_i142
#ISCELL
  standard offpage *
  page27_i143
#ISCELL
  standard offpage *
  page27_i144
#CELL
  pure_quanta q_res *
  page27_i145
#CELL
  pure_quanta q_res *
  page27_i146
#CELL
  pure_quanta q_res *
  page27_i147
#ISCELL
  standard offpage *
  page27_i148
#ISCELL
  standard offpage *
  page27_i155
#ISCELL
  standard offpage *
  page27_i156
#ISCELL
  standard offpage *
  page27_i158
#ISCELL
  logical_power vccaux15 *
  page27_i160
#ISCELL
  standard offpage *
  page27_i161
#ISCELL
  standard offpage *
  page27_i162
#CELL
  pure_quanta q_res *
  page27_i163
#ISCELL
  logical_power vccaux15 *
  page27_i164
#CELL
  pure_quanta q_res *
  page27_i165
#CELL
  pure_quanta q_cap *
  page27_i166
#ISCELL
  logical_power universal_gnd *
  page27_i167
#CELL
  pure_quanta q_res *
  page27_i168
#ISCELL
  standard offpage *
  page27_i169
#ISCELL
  standard offpage *
  page27_i170
#ISCELL
  standard offpage *
  page27_i173
#ISCELL
  standard offpage *
  page27_i174
#ISCELL
  standard offpage *
  page27_i175
#CELL
  pure_quanta q_res *
  page27_i177
#CELL
  pure_quanta q_res *
  page27_i179
#CELL
  pure_quanta q_res *
  page27_i181
#CELL
  pure_quanta q_res *
  page27_i182
#ISCELL
  standard offpage *
  page27_i183
#CELL
  pure_quanta q_res *
  page27_i184
#CELL
  pure_quanta bat54c *
  page27_i185
#ISCELL
  standard offpage *
  page27_i186
#ISCELL
  standard offpage *
  page27_i187
#CELL
  pure_quanta q_res *
  page27_i188
#ISCELL
  logical_power universal_power *
  page27_i189
#ISCELL
  standard offpage *
  page27_i202
#ISCELL
  logical_power universal_power *
  page27_i204
#ISCELL
  standard offpage *
  page27_i205
#ISCELL
  standard offpage *
  page27_i206
#ISCELL
  standard offpage *
  page27_i207
#ISCELL
  standard offpage *
  page27_i211
#CELL
  pure_quanta q_res *
  page27_i213
#ISCELL
  logical_power universal_power *
  page27_i214
#CELL
  pure_quanta q_res *
  page27_i217
#ISCELL
  logical_power universal_gnd *
  page27_i218
#CELL
  pure_quanta q_res *
  page27_i222
#ISCELL
  logical_power universal_gnd *
  page27_i223
#CELL
  pure_quanta q_res *
  page27_i228
#ISCELL
  standard offpage *
  page27_i229
#ISCELL
  standard offpage *
  page27_i230
#ISCELL
  logical_power vccaux15 *
  page27_i231
#ISCELL
  logical_power vccaux15 *
  page27_i232
#CELL
  pure_quanta q_res *
  page27_i233
#CELL
  pure_quanta q_res *
  page27_i234
#CELL
  pure_quanta q_res *
  page27_i235
#CELL
  pure_quanta q_res *
  page27_i236
#CELL
  pure_quanta q_res *
  page27_i237
#CELL
  pure_quanta q_res *
  page27_i238
#CELL
  pure_quanta q_res *
  page27_i239
#CELL
  pure_quanta q_res *
  page27_i240
#CELL
  pure_quanta q_res *
  page27_i241
#CELL
  pure_quanta q_res *
  page27_i242
#CELL
  pure_quanta 2n7002a7 *
  page27_i243
#CELL
  pure_quanta q_res *
  page27_i244
#ISCELL
  logical_power universal_gnd *
  page27_i245
#CELL
  pure_quanta q_res *
  page27_i246
#CELL
  pure_quanta q_res *
  page27_i247
#ISCELL
  standard offpage *
  page27_i75
#CELL
  pure_quanta q_res *
  page27_i84
#CELL
  pure_quanta q_res *
  page27_i85
#CELL
  pure_quanta q_res *
  page27_i86
#ISCELL
  logical_power universal_power *
  page27_i87
#CELL
  pure_quanta q_res *
  page27_i88
#CELL
  pure_quanta q_res *
  page27_i89
#CELL
  pure_quanta q_res *
  page27_i93
#CELL
  pure_quanta q_res *
  page27_i94
#CELL
  pure_quanta q_res *
  page27_i95
#CELL
  pure_quanta q_res *
  page27_i96
#CELL
  pure_quanta q_res *
  page27_i97
#CELL
  pure_quanta q_res *
  page27_i98
#CELL
  pure_quanta q_res *
  page27_i99
